# SCM (Grand Teton) — schematic netlist excerpt (pin names and nets, part order shuffled) for the footprints in the layout excerpt that follows; sources: Cadence DE-HDL packaged netlist, KiCad conversion of 12092022_DA0F0TMDCD0_F0T_Management_Board_D_brd_V3_OCP.brd

C92  Q_CAP  0.1UF 25V 10% X7R  pkg 0402  page 16 : A = P1V0_AUX ; B = GND
R837  Q_RES  33.2 1% CHIP  pkg 0402LF  page 34 : A = PWRGD_PSU_AC_PWROK ; B = PWRGD_PSU_AC_PWROK_PLD

(kicad_pcb
	(version 20260206)
	(generator "pcbnew")
	(generator_version "10.0")
	(general
		(thickness 1.6)
		(legacy_teardrops no)
	)
	(paper "A4")
	(title_block
		(title "12092022_DA0F0TMDCD0_F0T_Management_Board_D_brd_V3_OCP.brd")
		(comment 1 "Grand Teton / footprints 1359-1360 of 1440")
	)
	(layers
		(0 "F.Cu" signal "TOP")
		(4 "In1.Cu" signal "GND")
		(6 "In2.Cu" signal "IN1")
		(8 "In3.Cu" signal "GND1")
		(10 "In4.Cu" signal "IN2")
		(12 "In5.Cu" signal "VCC")
		(14 "In6.Cu" signal "VCC1")
		(16 "In7.Cu" signal "IN3")
		(18 "In8.Cu" signal "GND2")
		(20 "In9.Cu" signal "IN4")
		(22 "In10.Cu" signal "GND3")
		(2 "B.Cu" signal "BOTTOM")
		(9 "F.Adhes" user "F.Adhesive")
		(11 "B.Adhes" user "B.Adhesive")
		(13 "F.Paste" user "Package Geometry/Pastemask Top")
		(15 "B.Paste" user "Package Geometry/Pastemask Bottom")
		(5 "F.SilkS" user "Ref Des/Silkscreen Top")
		(7 "B.SilkS" user "Ref Des/Silkscreen Bottom")
		(1 "F.Mask" user "Board Geometry/Soldermask Top")
		(3 "B.Mask" user "Board Geometry/Soldermask Bottom")
		(17 "Dwgs.User" user "User.Drawings")
		(19 "Cmts.User" user "User.Comments")
		(21 "Eco1.User" user "User.Eco1")
		(23 "Eco2.User" user "User.Eco2")
		(25 "Edge.Cuts" user "Board Geometry/Outline")
		(27 "Margin" user)
		(31 "F.CrtYd" user "Package Geometry/Place Bound Top")
		(29 "B.CrtYd" user "Package Geometry/Place Bound Bottom")
		(35 "F.Fab" user "Ref Des/Assembly Top")
		(33 "B.Fab" user "Ref Des/Assembly Bottom")
	)
	(footprint ""
		(layer "B.Cu")
		(at 57.04586 -50.94097)
		(property "Reference" "C92"
			(at 0 0 0)
			(layer "B.SilkS")
			(hide yes)
			(effects
				(font
					(size 1.27 1.27)
				)
				(justify mirror)
			)
		)
		(property "Value" ""
			(at 0 0 0)
			(layer "B.Fab")
			(effects
				(font
					(size 1.27 1.27)
				)
				(justify mirror)
			)
		)
		(duplicate_pad_numbers_are_jumpers no)
		(fp_line
			(start -0.7874 -0.4064)
			(end -0.7874 0.4064)
			(stroke
				(width 0.1524)
				(type default)
			)
			(layer "B.SilkS")
		)
		(fp_line
			(start -0.7874 0.4064)
			(end 0.7874 0.4064)
			(stroke
				(width 0.1524)
				(type default)
			)
			(layer "B.SilkS")
		)
		(fp_line
			(start 0.7874 -0.4064)
			(end -0.7874 -0.4064)
			(stroke
				(width 0.1524)
				(type default)
			)
			(layer "B.SilkS")
		)
		(fp_line
			(start 0.7874 0.4064)
			(end 0.7874 -0.4064)
			(stroke
				(width 0.1524)
				(type default)
			)
			(layer "B.SilkS")
		)
		(fp_line
			(start -0.67945 -0.3048)
			(end -0.67945 0.3048)
			(stroke
				(width 0.1)
				(type default)
			)
			(layer "B.Fab")
		)
		(fp_line
			(start -0.67945 0.3048)
			(end -0.120396 0.3048)
			(stroke
				(width 0.1)
				(type default)
			)
			(layer "B.Fab")
		)
		(fp_line
			(start -0.12065 -0.3048)
			(end -0.67945 -0.3048)
			(stroke
				(width 0.1)
				(type default)
			)
			(layer "B.Fab")
		)
		(fp_line
			(start -0.12065 -0.2794)
			(end -0.12065 -0.3048)
			(stroke
				(width 0.1)
				(type default)
			)
			(layer "B.Fab")
		)
		(fp_line
			(start -0.120396 0.2794)
			(end 0.12065 0.2794)
			(stroke
				(width 0.1)
				(type default)
			)
			(layer "B.Fab")
		)
		(fp_line
			(start -0.120396 0.3048)
			(end -0.120396 0.2794)
			(stroke
				(width 0.1)
				(type default)
			)
			(layer "B.Fab")
		)
		(fp_line
			(start 0.12065 -0.305054)
			(end 0.12065 -0.2794)
			(stroke
				(width 0.1)
				(type default)
			)
			(layer "B.Fab")
		)
		(fp_line
			(start 0.12065 -0.2794)
			(end -0.12065 -0.2794)
			(stroke
				(width 0.1)
				(type default)
			)
			(layer "B.Fab")
		)
		(fp_line
			(start 0.12065 0.2794)
			(end 0.12065 0.3048)
			(stroke
				(width 0.1)
				(type default)
			)
			(layer "B.Fab")
		)
		(fp_line
			(start 0.12065 0.3048)
			(end 0.67945 0.3048)
			(stroke
				(width 0.1)
				(type default)
			)
			(layer "B.Fab")
		)
		(fp_line
			(start 0.67945 -0.305054)
			(end 0.12065 -0.305054)
			(stroke
				(width 0.1)
				(type default)
			)
			(layer "B.Fab")
		)
		(fp_line
			(start 0.67945 0.3048)
			(end 0.67945 -0.305054)
			(stroke
				(width 0.1)
				(type default)
			)
			(layer "B.Fab")
		)
		(pad "1" smd circle
			(at 0.40005 0 180)
			(size 0 0)
			(layers "B.Cu" "B.Mask" "B.Paste")
			(net "P1V0_AUX")
		)
		(pad "2" smd circle
			(at -0.40005 0 180)
			(size 0 0)
			(layers "B.Cu" "B.Mask" "B.Paste")
			(net "GND")
		)
	)
	(footprint ""
		(layer "B.Cu")
		(at 27.3304 -85.7758)
		(property "Reference" "R837"
			(at 0 0 0)
			(layer "B.SilkS")
			(hide yes)
			(effects
				(font
					(size 1.27 1.27)
				)
				(justify mirror)
			)
		)
		(property "Value" ""
			(at 0 0 0)
			(layer "B.Fab")
			(effects
				(font
					(size 1.27 1.27)
				)
				(justify mirror)
			)
		)
		(duplicate_pad_numbers_are_jumpers no)
		(fp_line
			(start -0.7874 -0.4064)
			(end -0.7874 0.4064)
			(stroke
				(width 0.1524)
				(type default)
			)
			(layer "B.SilkS")
		)
		(fp_line
			(start -0.7874 0.4064)
			(end 0.7874 0.4064)
			(stroke
				(width 0.1524)
				(type default)
			)
			(layer "B.SilkS")
		)
		(fp_line
			(start 0.7874 -0.4064)
			(end -0.7874 -0.4064)
			(stroke
				(width 0.1524)
				(type default)
			)
			(layer "B.SilkS")
		)
		(fp_line
			(start 0.7874 0.4064)
			(end 0.7874 -0.4064)
			(stroke
				(width 0.1524)
				(type default)
			)
			(layer "B.SilkS")
		)
		(fp_line
			(start -0.67945 -0.3048)
			(end -0.67945 0.3048)
			(stroke
				(width 0.1)
				(type default)
			)
			(layer "B.Fab")
		)
		(fp_line
			(start -0.67945 0.3048)
			(end -0.120396 0.3048)
			(stroke
				(width 0.1)
				(type default)
			)
			(layer "B.Fab")
		)
		(fp_line
			(start -0.12065 -0.3048)
			(end -0.67945 -0.3048)
			(stroke
				(width 0.1)
				(type default)
			)
			(layer "B.Fab")
		)
		(fp_line
			(start -0.12065 -0.2794)
			(end -0.12065 -0.3048)
			(stroke
				(width 0.1)
				(type default)
			)
			(layer "B.Fab")
		)
		(fp_line
			(start -0.120396 0.2794)
			(end 0.12065 0.2794)
			(stroke
				(width 0.1)
				(type default)
			)
			(layer "B.Fab")
		)
		(fp_line
			(start -0.120396 0.3048)
			(end -0.120396 0.2794)
			(stroke
				(width 0.1)
				(type default)
			)
			(layer "B.Fab")
		)
		(fp_line
			(start 0.12065 -0.305054)
			(end 0.12065 -0.2794)
			(stroke
				(width 0.1)
				(type default)
			)
			(layer "B.Fab")
		)
		(fp_line
			(start 0.12065 -0.2794)
			(end -0.12065 -0.2794)
			(stroke
				(width 0.1)
				(type default)
			)
			(layer "B.Fab")
		)
		(fp_line
			(start 0.12065 0.2794)
			(end 0.12065 0.3048)
			(stroke
				(width 0.1)
				(type default)
			)
			(layer "B.Fab")
		)
		(fp_line
			(start 0.12065 0.3048)
			(end 0.67945 0.3048)
			(stroke
				(width 0.1)
				(type default)
			)
			(layer "B.Fab")
		)
		(fp_line
			(start 0.67945 -0.305054)
			(end 0.12065 -0.305054)
			(stroke
				(width 0.1)
				(type default)
			)
			(layer "B.Fab")
		)
		(fp_line
			(start 0.67945 0.3048)
			(end 0.67945 -0.305054)
			(stroke
				(width 0.1)
				(type default)
			)
			(layer "B.Fab")
		)
		(pad "1" smd circle
			(at 0.40005 0 180)
			(size 0 0)
			(layers "B.Cu" "B.Mask" "B.Paste")
			(net "PWRGD_PSU_AC_PWROK")
		)
		(pad "2" smd circle
			(at -0.40005 0 180)
			(size 0 0)
			(layers "B.Cu" "B.Mask" "B.Paste")
			(net "PWRGD_PSU_AC_PWROK_PLD")
		)
	)
)
